(kicad_pcb
	(version 20260206)
	(generator "pcbnew")
	(generator_version "10.0")
	(general
		(thickness 1.6)
		(legacy_teardrops no)
	)
	(paper "A4")
	(title_block
		(title "9054_F0T_PDB_BD_GPU_F_V04_1213_1550_OCP.brd")
		(comment 1 "Grand Teton / footprints 320-322 of 608")
	)
	(layers
		(0 "F.Cu" signal "TOP")
		(4 "In1.Cu" signal "GND")
		(6 "In2.Cu" signal "IN1")
		(8 "In3.Cu" signal "GND1")
		(10 "In4.Cu" signal "VCC")
		(12 "In5.Cu" signal "VCC1")
		(14 "In6.Cu" signal "GND2")
		(16 "In7.Cu" signal "IN2")
		(18 "In8.Cu" signal "GND3")
		(2 "B.Cu" signal "BOTTOM")
		(9 "F.Adhes" user "F.Adhesive")
		(11 "B.Adhes" user "B.Adhesive")
		(13 "F.Paste" user "Package Geometry/Pastemask Top")
		(15 "B.Paste" user "Package Geometry/Pastemask Bottom")
		(5 "F.SilkS" user "Ref Des/Silkscreen Top")
		(7 "B.SilkS" user "Ref Des/Silkscreen Bottom")
		(1 "F.Mask" user "Board Geometry/Soldermask Top")
		(3 "B.Mask" user "Board Geometry/Soldermask Bottom")
		(17 "Dwgs.User" user "User.Drawings")
		(19 "Cmts.User" user "User.Comments")
		(21 "Eco1.User" user "User.Eco1")
		(23 "Eco2.User" user "User.Eco2")
		(25 "Edge.Cuts" user "Board Geometry/Outline")
		(27 "Margin" user)
		(31 "F.CrtYd" user "Package Geometry/Place Bound Top")
		(29 "B.CrtYd" user "Package Geometry/Place Bound Bottom")
		(35 "F.Fab" user "Ref Des/Assembly Top")
		(33 "B.Fab" user "Ref Des/Assembly Bottom")
	)
	(footprint ""
		(layer "F.Cu")
		(at 453.7964 -62.23 -90)
		(property "Reference" "PC51"
			(at 0 0 270)
			(layer "F.SilkS")
			(hide yes)
			(effects
				(font
					(size 1.27 1.27)
				)
			)
		)
		(property "Value" ""
			(at 0 0 270)
			(layer "F.Fab")
			(effects
				(font
					(size 1.27 1.27)
				)
			)
		)
		(duplicate_pad_numbers_are_jumpers no)
		(fp_line
			(start -0.7874 0.4064)
			(end -0.7874 -0.4064)
			(stroke
				(width 0.1524)
				(type default)
			)
			(layer "F.SilkS")
		)
		(fp_line
			(start 0.7874 0.4064)
			(end -0.7874 0.4064)
			(stroke
				(width 0.1524)
				(type default)
			)
			(layer "F.SilkS")
		)
		(fp_line
			(start -0.7874 -0.4064)
			(end 0.7874 -0.4064)
			(stroke
				(width 0.1524)
				(type default)
			)
			(layer "F.SilkS")
		)
		(fp_line
			(start 0.7874 -0.4064)
			(end 0.7874 0.4064)
			(stroke
				(width 0.1524)
				(type default)
			)
			(layer "F.SilkS")
		)
		(fp_line
			(start -0.67945 0.3048)
			(end -0.67945 -0.305054)
			(stroke
				(width 0.1)
				(type default)
			)
			(layer "F.Fab")
		)
		(fp_line
			(start -0.12065 0.3048)
			(end -0.67945 0.3048)
			(stroke
				(width 0.1)
				(type default)
			)
			(layer "F.Fab")
		)
		(fp_line
			(start 0.120396 0.3048)
			(end 0.120396 0.2794)
			(stroke
				(width 0.1)
				(type default)
			)
			(layer "F.Fab")
		)
		(fp_line
			(start 0.67945 0.3048)
			(end 0.120396 0.3048)
			(stroke
				(width 0.1)
				(type default)
			)
			(layer "F.Fab")
		)
		(fp_line
			(start -0.12065 0.2794)
			(end -0.12065 0.3048)
			(stroke
				(width 0.1)
				(type default)
			)
			(layer "F.Fab")
		)
		(fp_line
			(start 0.120396 0.2794)
			(end -0.12065 0.2794)
			(stroke
				(width 0.1)
				(type default)
			)
			(layer "F.Fab")
		)
		(fp_line
			(start -0.12065 -0.2794)
			(end 0.12065 -0.2794)
			(stroke
				(width 0.1)
				(type default)
			)
			(layer "F.Fab")
		)
		(fp_line
			(start 0.12065 -0.2794)
			(end 0.12065 -0.3048)
			(stroke
				(width 0.1)
				(type default)
			)
			(layer "F.Fab")
		)
		(fp_line
			(start 0.12065 -0.3048)
			(end 0.67945 -0.3048)
			(stroke
				(width 0.1)
				(type default)
			)
			(layer "F.Fab")
		)
		(fp_line
			(start 0.67945 -0.3048)
			(end 0.67945 0.3048)
			(stroke
				(width 0.1)
				(type default)
			)
			(layer "F.Fab")
		)
		(fp_line
			(start -0.67945 -0.305054)
			(end -0.12065 -0.305054)
			(stroke
				(width 0.1)
				(type default)
			)
			(layer "F.Fab")
		)
		(fp_line
			(start -0.12065 -0.305054)
			(end -0.12065 -0.2794)
			(stroke
				(width 0.1)
				(type default)
			)
			(layer "F.Fab")
		)
		(pad "1" smd circle
			(at -0.40005 0 270)
			(size 0 0)
			(layers "F.Cu" "F.Mask" "F.Paste")
			(net "P3V3_AUX")
		)
		(pad "2" smd circle
			(at 0.40005 0 270)
			(size 0 0)
			(layers "F.Cu" "F.Mask" "F.Paste")
			(net "GND")
		)
	)
	(footprint ""
		(layer "F.Cu")
		(at 427.228 -47.371 180)
		(property "Reference" "R49"
			(at 0 0 180)
			(layer "F.SilkS")
			(hide yes)
			(effects
				(font
					(size 1.27 1.27)
				)
			)
		)
		(property "Value" ""
			(at 0 0 180)
			(layer "F.Fab")
			(effects
				(font
					(size 1.27 1.27)
				)
			)
		)
		(duplicate_pad_numbers_are_jumpers no)
		(fp_line
			(start 0.7874 0.4064)
			(end -0.7874 0.4064)
			(stroke
				(width 0.1524)
				(type default)
			)
			(layer "F.SilkS")
		)
		(fp_line
			(start 0.7874 -0.4064)
			(end 0.7874 0.4064)
			(stroke
				(width 0.1524)
				(type default)
			)
			(layer "F.SilkS")
		)
		(fp_line
			(start -0.7874 0.4064)
			(end -0.7874 -0.4064)
			(stroke
				(width 0.1524)
				(type default)
			)
			(layer "F.SilkS")
		)
		(fp_line
			(start -0.7874 -0.4064)
			(end 0.7874 -0.4064)
			(stroke
				(width 0.1524)
				(type default)
			)
			(layer "F.SilkS")
		)
		(fp_line
			(start 0.67945 0.3048)
			(end 0.120396 0.3048)
			(stroke
				(width 0.1)
				(type default)
			)
			(layer "F.Fab")
		)
		(fp_line
			(start 0.67945 -0.3048)
			(end 0.67945 0.3048)
			(stroke
				(width 0.1)
				(type default)
			)
			(layer "F.Fab")
		)
		(fp_line
			(start 0.12065 -0.2794)
			(end 0.12065 -0.3048)
			(stroke
				(width 0.1)
				(type default)
			)
			(layer "F.Fab")
		)
		(fp_line
			(start 0.12065 -0.3048)
			(end 0.67945 -0.3048)
			(stroke
				(width 0.1)
				(type default)
			)
			(layer "F.Fab")
		)
		(fp_line
			(start 0.120396 0.3048)
			(end 0.120396 0.2794)
			(stroke
				(width 0.1)
				(type default)
			)
			(layer "F.Fab")
		)
		(fp_line
			(start 0.120396 0.2794)
			(end -0.12065 0.2794)
			(stroke
				(width 0.1)
				(type default)
			)
			(layer "F.Fab")
		)
		(fp_line
			(start -0.12065 0.3048)
			(end -0.67945 0.3048)
			(stroke
				(width 0.1)
				(type default)
			)
			(layer "F.Fab")
		)
		(fp_line
			(start -0.12065 0.2794)
			(end -0.12065 0.3048)
			(stroke
				(width 0.1)
				(type default)
			)
			(layer "F.Fab")
		)
		(fp_line
			(start -0.12065 -0.2794)
			(end 0.12065 -0.2794)
			(stroke
				(width 0.1)
				(type default)
			)
			(layer "F.Fab")
		)
		(fp_line
			(start -0.12065 -0.305054)
			(end -0.12065 -0.2794)
			(stroke
				(width 0.1)
				(type default)
			)
			(layer "F.Fab")
		)
		(fp_line
			(start -0.67945 0.3048)
			(end -0.67945 -0.305054)
			(stroke
				(width 0.1)
				(type default)
			)
			(layer "F.Fab")
		)
		(fp_line
			(start -0.67945 -0.305054)
			(end -0.12065 -0.305054)
			(stroke
				(width 0.1)
				(type default)
			)
			(layer "F.Fab")
		)
		(pad "1" smd circle
			(at -0.40005 0 180)
			(size 0 0)
			(layers "F.Cu" "F.Mask" "F.Paste")
			(net "SMB_PDB_MISC_SDA")
		)
		(pad "2" smd circle
			(at 0.40005 0 180)
			(size 0 0)
			(layers "F.Cu" "F.Mask" "F.Paste")
			(net "SMB_IOEXP_SDA")
		)
	)
	(footprint ""
		(layer "F.Cu")
		(at 168.956736 -65.024 180)
		(property "Reference" "PR7032"
			(at 0 0 180)
			(layer "F.SilkS")
			(hide yes)
			(effects
				(font
					(size 1.27 1.27)
				)
			)
		)
		(property "Value" ""
			(at 0 0 180)
			(layer "F.Fab")
			(effects
				(font
					(size 1.27 1.27)
				)
			)
		)
		(duplicate_pad_numbers_are_jumpers no)
		(fp_line
			(start 0.7874 0.4064)
			(end -0.7874 0.4064)
			(stroke
				(width 0.1524)
				(type default)
			)
			(layer "F.SilkS")
		)
		(fp_line
			(start 0.7874 -0.4064)
			(end 0.7874 0.4064)
			(stroke
				(width 0.1524)
				(type default)
			)
			(layer "F.SilkS")
		)
		(fp_line
			(start -0.7874 0.4064)
			(end -0.7874 -0.4064)
			(stroke
				(width 0.1524)
				(type default)
			)
			(layer "F.SilkS")
		)
		(fp_line
			(start -0.7874 -0.4064)
			(end 0.7874 -0.4064)
			(stroke
				(width 0.1524)
				(type default)
			)
			(layer "F.SilkS")
		)
		(fp_line
			(start 0.67945 0.3048)
			(end 0.120396 0.3048)
			(stroke
				(width 0.1)
				(type default)
			)
			(layer "F.Fab")
		)
		(fp_line
			(start 0.67945 -0.3048)
			(end 0.67945 0.3048)
			(stroke
				(width 0.1)
				(type default)
			)
			(layer "F.Fab")
		)
		(fp_line
			(start 0.12065 -0.2794)
			(end 0.12065 -0.3048)
			(stroke
				(width 0.1)
				(type default)
			)
			(layer "F.Fab")
		)
		(fp_line
			(start 0.12065 -0.3048)
			(end 0.67945 -0.3048)
			(stroke
				(width 0.1)
				(type default)
			)
			(layer "F.Fab")
		)
		(fp_line
			(start 0.120396 0.3048)
			(end 0.120396 0.2794)
			(stroke
				(width 0.1)
				(type default)
			)
			(layer "F.Fab")
		)
		(fp_line
			(start 0.120396 0.2794)
			(end -0.12065 0.2794)
			(stroke
				(width 0.1)
				(type default)
			)
			(layer "F.Fab")
		)
		(fp_line
			(start -0.12065 0.3048)
			(end -0.67945 0.3048)
			(stroke
				(width 0.1)
				(type default)
			)
			(layer "F.Fab")
		)
		(fp_line
			(start -0.12065 0.2794)
			(end -0.12065 0.3048)
			(stroke
				(width 0.1)
				(type default)
			)
			(layer "F.Fab")
		)
		(fp_line
			(start -0.12065 -0.2794)
			(end 0.12065 -0.2794)
			(stroke
				(width 0.1)
				(type default)
			)
			(layer "F.Fab")
		)
		(fp_line
			(start -0.12065 -0.305054)
			(end -0.12065 -0.2794)
			(stroke
				(width 0.1)
				(type default)
			)
			(layer "F.Fab")
		)
		(fp_line
			(start -0.67945 0.3048)
			(end -0.67945 -0.305054)
			(stroke
				(width 0.1)
				(type default)
			)
			(layer "F.Fab")
		)
		(fp_line
			(start -0.67945 -0.305054)
			(end -0.12065 -0.305054)
			(stroke
				(width 0.1)
				(type default)
			)
			(layer "F.Fab")
		)
		(pad "1" smd circle
			(at -0.40005 0 180)
			(size 0 0)
			(layers "F.Cu" "F.Mask" "F.Paste")
			(net "P52V_HS2_EFAULT_R")
		)
		(pad "2" smd circle
			(at 0.40005 0 180)
			(size 0 0)
			(layers "F.Cu" "F.Mask" "F.Paste")
			(net "P52V_HS2_EFAULT")
		)
	)
)
